(kicad_pcb
	(version 20260206)
	(generator "pcbnew")
	(generator_version "10.0")
	(general
		(thickness 1.6)
		(legacy_teardrops no)
	)
	(paper "A4")
	(title_block
		(title "01162023_DA0F0TEBIF0_F0T_Expander_BD_F_brd_V02_OCP.brd")
		(comment 1 "Grand Teton / footprints 8456-8463 of 9728")
	)
	(layers
		(0 "F.Cu" signal "TOP")
		(4 "In1.Cu" signal "GND")
		(6 "In2.Cu" signal "VCC")
		(8 "In3.Cu" signal "VCC1")
		(10 "In4.Cu" signal "GND1")
		(12 "In5.Cu" signal "IN1")
		(14 "In6.Cu" signal "GND2")
		(16 "In7.Cu" signal "IN2")
		(18 "In8.Cu" signal "GND3")
		(20 "In9.Cu" signal "IN3")
		(22 "In10.Cu" signal "GND4")
		(24 "In11.Cu" signal "IN4")
		(26 "In12.Cu" signal "GND5")
		(28 "In13.Cu" signal "IN5")
		(30 "In14.Cu" signal "GND6")
		(32 "In15.Cu" signal "IN6")
		(34 "In16.Cu" signal "GND7")
		(2 "B.Cu" signal "BOTTOM")
		(9 "F.Adhes" user "F.Adhesive")
		(11 "B.Adhes" user "B.Adhesive")
		(13 "F.Paste" user "Package Geometry/Pastemask Top")
		(15 "B.Paste" user "Package Geometry/Pastemask Bottom")
		(5 "F.SilkS" user "Ref Des/Silkscreen Top")
		(7 "B.SilkS" user "Ref Des/Silkscreen Bottom")
		(1 "F.Mask" user "Board Geometry/Soldermask Top")
		(3 "B.Mask" user "Board Geometry/Soldermask Bottom")
		(17 "Dwgs.User" user "User.Drawings")
		(19 "Cmts.User" user "User.Comments")
		(21 "Eco1.User" user "User.Eco1")
		(23 "Eco2.User" user "User.Eco2")
		(25 "Edge.Cuts" user "Board Geometry/Outline")
		(27 "Margin" user)
		(31 "F.CrtYd" user "Package Geometry/Place Bound Top")
		(29 "B.CrtYd" user "Package Geometry/Place Bound Bottom")
		(35 "F.Fab" user "Ref Des/Assembly Top")
		(33 "B.Fab" user "Ref Des/Assembly Bottom")
	)
	(footprint ""
		(layer "B.Cu")
		(at 71.049896 -296.37482 180)
		(property "Reference" "C2926"
			(at 0 0 0)
			(layer "B.SilkS")
			(hide yes)
			(effects
				(font
					(size 1.27 1.27)
				)
				(justify mirror)
			)
		)
		(property "Value" ""
			(at 0 0 0)
			(layer "B.Fab")
			(effects
				(font
					(size 1.27 1.27)
				)
				(justify mirror)
			)
		)
		(duplicate_pad_numbers_are_jumpers no)
		(fp_line
			(start 0.299974 0.150114)
			(end 0.299974 -0.150114)
			(stroke
				(width 0.1)
				(type default)
			)
			(layer "B.Fab")
		)
		(fp_line
			(start 0.299974 -0.150114)
			(end -0.299974 -0.150114)
			(stroke
				(width 0.1)
				(type default)
			)
			(layer "B.Fab")
		)
		(fp_line
			(start -0.299974 0.150114)
			(end 0.299974 0.150114)
			(stroke
				(width 0.1)
				(type default)
			)
			(layer "B.Fab")
		)
		(fp_line
			(start -0.299974 -0.150114)
			(end -0.299974 0.150114)
			(stroke
				(width 0.1)
				(type default)
			)
			(layer "B.Fab")
		)
		(pad "1" smd rect
			(at 0.2667 0)
			(size 0.3048 0.381)
			(layers "B.Cu" "B.Mask" "B.Paste")
			(net "P1V25_PEX0")
		)
		(pad "2" smd rect
			(at -0.2667 0)
			(size 0.3048 0.381)
			(layers "B.Cu" "B.Mask" "B.Paste")
			(net "GND")
		)
	)
	(footprint ""
		(layer "B.Cu")
		(at 335.279746 -323.15531 -90)
		(property "Reference" "R6505"
			(at 0 0 90)
			(layer "B.SilkS")
			(hide yes)
			(effects
				(font
					(size 1.27 1.27)
				)
				(justify mirror)
			)
		)
		(property "Value" ""
			(at 0 0 90)
			(layer "B.Fab")
			(effects
				(font
					(size 1.27 1.27)
				)
				(justify mirror)
			)
		)
		(duplicate_pad_numbers_are_jumpers no)
		(fp_line
			(start -0.7874 0.4064)
			(end 0.7874 0.4064)
			(stroke
				(width 0.1524)
				(type default)
			)
			(layer "B.SilkS")
		)
		(fp_line
			(start 0.7874 0.4064)
			(end 0.7874 -0.4064)
			(stroke
				(width 0.1524)
				(type default)
			)
			(layer "B.SilkS")
		)
		(fp_line
			(start -0.7874 -0.4064)
			(end -0.7874 0.4064)
			(stroke
				(width 0.1524)
				(type default)
			)
			(layer "B.SilkS")
		)
		(fp_line
			(start 0.7874 -0.4064)
			(end -0.7874 -0.4064)
			(stroke
				(width 0.1524)
				(type default)
			)
			(layer "B.SilkS")
		)
		(fp_line
			(start -0.67945 0.3048)
			(end -0.120396 0.3048)
			(stroke
				(width 0.1)
				(type default)
			)
			(layer "B.Fab")
		)
		(fp_line
			(start -0.120396 0.3048)
			(end -0.120396 0.2794)
			(stroke
				(width 0.1)
				(type default)
			)
			(layer "B.Fab")
		)
		(fp_line
			(start 0.12065 0.3048)
			(end 0.67945 0.3048)
			(stroke
				(width 0.1)
				(type default)
			)
			(layer "B.Fab")
		)
		(fp_line
			(start 0.67945 0.3048)
			(end 0.67945 -0.305054)
			(stroke
				(width 0.1)
				(type default)
			)
			(layer "B.Fab")
		)
		(fp_line
			(start -0.120396 0.2794)
			(end 0.12065 0.2794)
			(stroke
				(width 0.1)
				(type default)
			)
			(layer "B.Fab")
		)
		(fp_line
			(start 0.12065 0.2794)
			(end 0.12065 0.3048)
			(stroke
				(width 0.1)
				(type default)
			)
			(layer "B.Fab")
		)
		(fp_line
			(start -0.12065 -0.2794)
			(end -0.12065 -0.3048)
			(stroke
				(width 0.1)
				(type default)
			)
			(layer "B.Fab")
		)
		(fp_line
			(start 0.12065 -0.2794)
			(end -0.12065 -0.2794)
			(stroke
				(width 0.1)
				(type default)
			)
			(layer "B.Fab")
		)
		(fp_line
			(start -0.67945 -0.3048)
			(end -0.67945 0.3048)
			(stroke
				(width 0.1)
				(type default)
			)
			(layer "B.Fab")
		)
		(fp_line
			(start -0.12065 -0.3048)
			(end -0.67945 -0.3048)
			(stroke
				(width 0.1)
				(type default)
			)
			(layer "B.Fab")
		)
		(fp_line
			(start 0.12065 -0.305054)
			(end 0.12065 -0.2794)
			(stroke
				(width 0.1)
				(type default)
			)
			(layer "B.Fab")
		)
		(fp_line
			(start 0.67945 -0.305054)
			(end 0.12065 -0.305054)
			(stroke
				(width 0.1)
				(type default)
			)
			(layer "B.Fab")
		)
		(pad "1" smd circle
			(at 0.40005 0 90)
			(size 0 0)
			(layers "B.Cu" "B.Mask" "B.Paste")
			(net "P0V8_SERDES_VDDA_PEX2")
		)
		(pad "2" smd circle
			(at -0.40005 0 90)
			(size 0 0)
			(layers "B.Cu" "B.Mask" "B.Paste")
			(net "P0V8_SERDES_VDDA_PEX2_C0")
		)
	)
	(footprint ""
		(layer "B.Cu")
		(at 68.941442 -286.874966)
		(property "Reference" "C2996"
			(at 0 0 0)
			(layer "B.SilkS")
			(hide yes)
			(effects
				(font
					(size 1.27 1.27)
				)
				(justify mirror)
			)
		)
		(property "Value" ""
			(at 0 0 0)
			(layer "B.Fab")
			(effects
				(font
					(size 1.27 1.27)
				)
				(justify mirror)
			)
		)
		(duplicate_pad_numbers_are_jumpers no)
		(fp_line
			(start -0.299974 -0.150114)
			(end -0.299974 0.150114)
			(stroke
				(width 0.1)
				(type default)
			)
			(layer "B.Fab")
		)
		(fp_line
			(start -0.299974 0.150114)
			(end 0.299974 0.150114)
			(stroke
				(width 0.1)
				(type default)
			)
			(layer "B.Fab")
		)
		(fp_line
			(start 0.299974 -0.150114)
			(end -0.299974 -0.150114)
			(stroke
				(width 0.1)
				(type default)
			)
			(layer "B.Fab")
		)
		(fp_line
			(start 0.299974 0.150114)
			(end 0.299974 -0.150114)
			(stroke
				(width 0.1)
				(type default)
			)
			(layer "B.Fab")
		)
		(pad "1" smd rect
			(at 0.2667 0 180)
			(size 0.3048 0.381)
			(layers "B.Cu" "B.Mask" "B.Paste")
			(net "P1V8_VDDA_PEX0")
		)
		(pad "2" smd rect
			(at -0.2667 0 180)
			(size 0.3048 0.381)
			(layers "B.Cu" "B.Mask" "B.Paste")
			(net "GND")
		)
	)
	(footprint ""
		(layer "B.Cu")
		(at 300.591474 -221.694502 -90)
		(property "Reference" "R6176"
			(at 0 0 90)
			(layer "B.SilkS")
			(hide yes)
			(effects
				(font
					(size 1.27 1.27)
				)
				(justify mirror)
			)
		)
		(property "Value" ""
			(at 0 0 90)
			(layer "B.Fab")
			(effects
				(font
					(size 1.27 1.27)
				)
				(justify mirror)
			)
		)
		(duplicate_pad_numbers_are_jumpers no)
		(fp_line
			(start -0.7874 0.4064)
			(end 0.7874 0.4064)
			(stroke
				(width 0.1524)
				(type default)
			)
			(layer "B.SilkS")
		)
		(fp_line
			(start 0.7874 0.4064)
			(end 0.7874 -0.4064)
			(stroke
				(width 0.1524)
				(type default)
			)
			(layer "B.SilkS")
		)
		(fp_line
			(start -0.7874 -0.4064)
			(end -0.7874 0.4064)
			(stroke
				(width 0.1524)
				(type default)
			)
			(layer "B.SilkS")
		)
		(fp_line
			(start 0.7874 -0.4064)
			(end -0.7874 -0.4064)
			(stroke
				(width 0.1524)
				(type default)
			)
			(layer "B.SilkS")
		)
		(fp_line
			(start -0.67945 0.3048)
			(end -0.120396 0.3048)
			(stroke
				(width 0.1)
				(type default)
			)
			(layer "B.Fab")
		)
		(fp_line
			(start -0.120396 0.3048)
			(end -0.120396 0.2794)
			(stroke
				(width 0.1)
				(type default)
			)
			(layer "B.Fab")
		)
		(fp_line
			(start 0.12065 0.3048)
			(end 0.67945 0.3048)
			(stroke
				(width 0.1)
				(type default)
			)
			(layer "B.Fab")
		)
		(fp_line
			(start 0.67945 0.3048)
			(end 0.67945 -0.305054)
			(stroke
				(width 0.1)
				(type default)
			)
			(layer "B.Fab")
		)
		(fp_line
			(start -0.120396 0.2794)
			(end 0.12065 0.2794)
			(stroke
				(width 0.1)
				(type default)
			)
			(layer "B.Fab")
		)
		(fp_line
			(start 0.12065 0.2794)
			(end 0.12065 0.3048)
			(stroke
				(width 0.1)
				(type default)
			)
			(layer "B.Fab")
		)
		(fp_line
			(start -0.12065 -0.2794)
			(end -0.12065 -0.3048)
			(stroke
				(width 0.1)
				(type default)
			)
			(layer "B.Fab")
		)
		(fp_line
			(start 0.12065 -0.2794)
			(end -0.12065 -0.2794)
			(stroke
				(width 0.1)
				(type default)
			)
			(layer "B.Fab")
		)
		(fp_line
			(start -0.67945 -0.3048)
			(end -0.67945 0.3048)
			(stroke
				(width 0.1)
				(type default)
			)
			(layer "B.Fab")
		)
		(fp_line
			(start -0.12065 -0.3048)
			(end -0.67945 -0.3048)
			(stroke
				(width 0.1)
				(type default)
			)
			(layer "B.Fab")
		)
		(fp_line
			(start 0.12065 -0.305054)
			(end 0.12065 -0.2794)
			(stroke
				(width 0.1)
				(type default)
			)
			(layer "B.Fab")
		)
		(fp_line
			(start 0.67945 -0.305054)
			(end 0.12065 -0.305054)
			(stroke
				(width 0.1)
				(type default)
			)
			(layer "B.Fab")
		)
		(pad "1" smd circle
			(at 0.40005 0 90)
			(size 0 0)
			(layers "B.Cu" "B.Mask" "B.Paste")
			(net "GND")
		)
		(pad "2" smd circle
			(at -0.40005 0 90)
			(size 0 0)
			(layers "B.Cu" "B.Mask" "B.Paste")
			(net "RST_GPU_PERST_2_N")
		)
	)
	(footprint ""
		(layer "B.Cu")
		(at 166.265098 -301.599854 -90)
		(property "Reference" "C1444"
			(at 0 0 90)
			(layer "B.SilkS")
			(hide yes)
			(effects
				(font
					(size 1.27 1.27)
				)
				(justify mirror)
			)
		)
		(property "Value" ""
			(at 0 0 90)
			(layer "B.Fab")
			(effects
				(font
					(size 1.27 1.27)
				)
				(justify mirror)
			)
		)
		(duplicate_pad_numbers_are_jumpers no)
		(fp_line
			(start -0.299974 0.150114)
			(end 0.299974 0.150114)
			(stroke
				(width 0.1)
				(type default)
			)
			(layer "B.Fab")
		)
		(fp_line
			(start 0.299974 0.150114)
			(end 0.299974 -0.150114)
			(stroke
				(width 0.1)
				(type default)
			)
			(layer "B.Fab")
		)
		(fp_line
			(start -0.299974 -0.150114)
			(end -0.299974 0.150114)
			(stroke
				(width 0.1)
				(type default)
			)
			(layer "B.Fab")
		)
		(fp_line
			(start 0.299974 -0.150114)
			(end -0.299974 -0.150114)
			(stroke
				(width 0.1)
				(type default)
			)
			(layer "B.Fab")
		)
		(pad "1" smd rect
			(at 0.2667 0 90)
			(size 0.3048 0.381)
			(layers "B.Cu" "B.Mask" "B.Paste")
			(net "P0V8_SERDES_VDDA_PEX1")
		)
		(pad "2" smd rect
			(at -0.2667 0 90)
			(size 0.3048 0.381)
			(layers "B.Cu" "B.Mask" "B.Paste")
			(net "GND")
		)
	)
	(footprint ""
		(layer "B.Cu")
		(at 416.024822 -286.399732 90)
		(property "Reference" "C3482"
			(at 0 0 90)
			(layer "B.SilkS")
			(hide yes)
			(effects
				(font
					(size 1.27 1.27)
				)
				(justify mirror)
			)
		)
		(property "Value" ""
			(at 0 0 90)
			(layer "B.Fab")
			(effects
				(font
					(size 1.27 1.27)
				)
				(justify mirror)
			)
		)
		(duplicate_pad_numbers_are_jumpers no)
		(fp_line
			(start 0.299974 -0.150114)
			(end -0.299974 -0.150114)
			(stroke
				(width 0.1)
				(type default)
			)
			(layer "B.Fab")
		)
		(fp_line
			(start -0.299974 -0.150114)
			(end -0.299974 0.150114)
			(stroke
				(width 0.1)
				(type default)
			)
			(layer "B.Fab")
		)
		(fp_line
			(start 0.299974 0.150114)
			(end 0.299974 -0.150114)
			(stroke
				(width 0.1)
				(type default)
			)
			(layer "B.Fab")
		)
		(fp_line
			(start -0.299974 0.150114)
			(end 0.299974 0.150114)
			(stroke
				(width 0.1)
				(type default)
			)
			(layer "B.Fab")
		)
		(pad "1" smd rect
			(at 0.2667 0 270)
			(size 0.3048 0.381)
			(layers "B.Cu" "B.Mask" "B.Paste")
			(net "P1V25_SERDES_VDDPLL_PEX3")
		)
		(pad "2" smd rect
			(at -0.2667 0 270)
			(size 0.3048 0.381)
			(layers "B.Cu" "B.Mask" "B.Paste")
			(net "GND")
		)
	)
	(footprint ""
		(layer "B.Cu")
		(at 347.726 -207.772 -90)
		(property "Reference" "R4151"
			(at 0 0 90)
			(layer "B.SilkS")
			(hide yes)
			(effects
				(font
					(size 1.27 1.27)
				)
				(justify mirror)
			)
		)
		(property "Value" ""
			(at 0 0 90)
			(layer "B.Fab")
			(effects
				(font
					(size 1.27 1.27)
				)
				(justify mirror)
			)
		)
		(duplicate_pad_numbers_are_jumpers no)
		(fp_line
			(start -0.7874 0.4064)
			(end 0.7874 0.4064)
			(stroke
				(width 0.1524)
				(type default)
			)
			(layer "B.SilkS")
		)
		(fp_line
			(start 0.7874 0.4064)
			(end 0.7874 -0.4064)
			(stroke
				(width 0.1524)
				(type default)
			)
			(layer "B.SilkS")
		)
		(fp_line
			(start -0.7874 -0.4064)
			(end -0.7874 0.4064)
			(stroke
				(width 0.1524)
				(type default)
			)
			(layer "B.SilkS")
		)
		(fp_line
			(start 0.7874 -0.4064)
			(end -0.7874 -0.4064)
			(stroke
				(width 0.1524)
				(type default)
			)
			(layer "B.SilkS")
		)
		(fp_line
			(start -0.67945 0.3048)
			(end -0.120396 0.3048)
			(stroke
				(width 0.1)
				(type default)
			)
			(layer "B.Fab")
		)
		(fp_line
			(start -0.120396 0.3048)
			(end -0.120396 0.2794)
			(stroke
				(width 0.1)
				(type default)
			)
			(layer "B.Fab")
		)
		(fp_line
			(start 0.12065 0.3048)
			(end 0.67945 0.3048)
			(stroke
				(width 0.1)
				(type default)
			)
			(layer "B.Fab")
		)
		(fp_line
			(start 0.67945 0.3048)
			(end 0.67945 -0.305054)
			(stroke
				(width 0.1)
				(type default)
			)
			(layer "B.Fab")
		)
		(fp_line
			(start -0.120396 0.2794)
			(end 0.12065 0.2794)
			(stroke
				(width 0.1)
				(type default)
			)
			(layer "B.Fab")
		)
		(fp_line
			(start 0.12065 0.2794)
			(end 0.12065 0.3048)
			(stroke
				(width 0.1)
				(type default)
			)
			(layer "B.Fab")
		)
		(fp_line
			(start -0.12065 -0.2794)
			(end -0.12065 -0.3048)
			(stroke
				(width 0.1)
				(type default)
			)
			(layer "B.Fab")
		)
		(fp_line
			(start 0.12065 -0.2794)
			(end -0.12065 -0.2794)
			(stroke
				(width 0.1)
				(type default)
			)
			(layer "B.Fab")
		)
		(fp_line
			(start -0.67945 -0.3048)
			(end -0.67945 0.3048)
			(stroke
				(width 0.1)
				(type default)
			)
			(layer "B.Fab")
		)
		(fp_line
			(start -0.12065 -0.3048)
			(end -0.67945 -0.3048)
			(stroke
				(width 0.1)
				(type default)
			)
			(layer "B.Fab")
		)
		(fp_line
			(start 0.12065 -0.305054)
			(end 0.12065 -0.2794)
			(stroke
				(width 0.1)
				(type default)
			)
			(layer "B.Fab")
		)
		(fp_line
			(start 0.67945 -0.305054)
			(end 0.12065 -0.305054)
			(stroke
				(width 0.1)
				(type default)
			)
			(layer "B.Fab")
		)
		(pad "1" smd circle
			(at 0.40005 0 90)
			(size 0 0)
			(layers "B.Cu" "B.Mask" "B.Paste")
			(net "PRSNT_SSD4_FPGA_R_N")
		)
		(pad "2" smd circle
			(at -0.40005 0 90)
			(size 0 0)
			(layers "B.Cu" "B.Mask" "B.Paste")
			(net "PRSNT_SSD4_FPGA_N")
		)
	)
	(footprint ""
		(layer "B.Cu")
		(at 357.436928 -325.336408 -90)
		(property "Reference" "C4383"
			(at 0 0 90)
			(layer "B.SilkS")
			(hide yes)
			(effects
				(font
					(size 1.27 1.27)
				)
				(justify mirror)
			)
		)
		(property "Value" ""
			(at 0 0 90)
			(layer "B.Fab")
			(effects
				(font
					(size 1.27 1.27)
				)
				(justify mirror)
			)
		)
		(duplicate_pad_numbers_are_jumpers no)
		(fp_line
			(start -1.2954 0.5842)
			(end 1.2954 0.5842)
			(stroke
				(width 0.1524)
				(type default)
			)
			(layer "B.SilkS")
		)
		(fp_line
			(start 1.2954 0.5842)
			(end 1.2954 -0.5842)
			(stroke
				(width 0.1524)
				(type default)
			)
			(layer "B.SilkS")
		)
		(fp_line
			(start -1.2954 -0.5842)
			(end -1.2954 0.5842)
			(stroke
				(width 0.1524)
				(type default)
			)
			(layer "B.SilkS")
		)
		(fp_line
			(start 1.2954 -0.5842)
			(end -1.2954 -0.5842)
			(stroke
				(width 0.1524)
				(type default)
			)
			(layer "B.SilkS")
		)
		(fp_line
			(start -0.8636 0.4572)
			(end 0.8636 0.4572)
			(stroke
				(width 0.1)
				(type default)
			)
			(layer "B.Fab")
		)
		(fp_line
			(start 0.8636 0.4572)
			(end 0.8636 0.4064)
			(stroke
				(width 0.1)
				(type default)
			)
			(layer "B.Fab")
		)
		(fp_line
			(start -1.1938 0.4064)
			(end -0.8636 0.4064)
			(stroke
				(width 0.1)
				(type default)
			)
			(layer "B.Fab")
		)
		(fp_line
			(start -0.8636 0.4064)
			(end -0.8636 0.4572)
			(stroke
				(width 0.1)
				(type default)
			)
			(layer "B.Fab")
		)
		(fp_line
			(start 0.8636 0.4064)
			(end 1.1938 0.4064)
			(stroke
				(width 0.1)
				(type default)
			)
			(layer "B.Fab")
		)
		(fp_line
			(start 1.1938 0.4064)
			(end 1.1938 -0.4064)
			(stroke
				(width 0.1)
				(type default)
			)
			(layer "B.Fab")
		)
		(fp_line
			(start -1.1938 -0.4064)
			(end -1.1938 0.4064)
			(stroke
				(width 0.1)
				(type default)
			)
			(layer "B.Fab")
		)
		(fp_line
			(start -0.8636 -0.4064)
			(end -1.1938 -0.4064)
			(stroke
				(width 0.1)
				(type default)
			)
			(layer "B.Fab")
		)
		(fp_line
			(start 0.8636 -0.4064)
			(end 0.8636 -0.4572)
			(stroke
				(width 0.1)
				(type default)
			)
			(layer "B.Fab")
		)
		(fp_line
			(start 1.1938 -0.4064)
			(end 0.8636 -0.4064)
			(stroke
				(width 0.1)
				(type default)
			)
			(layer "B.Fab")
		)
		(fp_line
			(start -0.8636 -0.4572)
			(end -0.8636 -0.4064)
			(stroke
				(width 0.1)
				(type default)
			)
			(layer "B.Fab")
		)
		(fp_line
			(start 0.8636 -0.4572)
			(end -0.8636 -0.4572)
			(stroke
				(width 0.1)
				(type default)
			)
			(layer "B.Fab")
		)
		(pad "1" smd rect
			(at 0.7366 0 180)
			(size 0.7112 0.8128)
			(layers "B.Cu" "B.Mask" "B.Paste")
			(net "P0V8_SERDES_VDDA_PEX3_C9")
		)
		(pad "2" smd rect
			(at -0.7366 0 180)
			(size 0.7112 0.8128)
			(layers "B.Cu" "B.Mask" "B.Paste")
			(net "GND")
		)
	)
)
